(kicad_pcb
	(version 20260206)
	(generator "pcbnew")
	(generator_version "10.0")
	(general
		(thickness 1.6)
		(legacy_teardrops no)
	)
	(paper "A4")
	(title_block
		(title "v2-pdb — ms_pdb_v2.brd")
		(comment 1 "Open CloudServer (Microsoft) / footprints 34-41 of 348")
	)
	(layers
		(0 "F.Cu" signal "TOP")
		(4 "In1.Cu" signal "GND")
		(6 "In2.Cu" signal "IN1")
		(8 "In3.Cu" signal "VCC")
		(10 "In4.Cu" signal "VCC1")
		(12 "In5.Cu" signal "IN2")
		(14 "In6.Cu" signal "GND1")
		(2 "B.Cu" signal "BOTTOM")
		(9 "F.Adhes" user "F.Adhesive")
		(11 "B.Adhes" user "B.Adhesive")
		(13 "F.Paste" user "Package Geometry/Pastemask Top")
		(15 "B.Paste" user "Package Geometry/Pastemask Bottom")
		(5 "F.SilkS" user "Ref Des/Silkscreen Top")
		(7 "B.SilkS" user "Ref Des/Silkscreen Bottom")
		(1 "F.Mask" user "Board Geometry/Soldermask Top")
		(3 "B.Mask" user "Board Geometry/Soldermask Bottom")
		(17 "Dwgs.User" user "User.Drawings")
		(19 "Cmts.User" user "User.Comments")
		(21 "Eco1.User" user "User.Eco1")
		(23 "Eco2.User" user "User.Eco2")
		(25 "Edge.Cuts" user "Board Geometry/Outline")
		(27 "Margin" user)
		(31 "F.CrtYd" user "Package Geometry/Place Bound Top")
		(29 "B.CrtYd" user "Package Geometry/Place Bound Bottom")
		(35 "F.Fab" user "Ref Des/Assembly Top")
		(33 "B.Fab" user "Ref Des/Assembly Bottom")
	)
	(footprint ""
		(layer "F.Cu")
		(at 74.0537 -463.542634 -90)
		(property "Reference" "C73"
			(at -2.840736 0.630936 90)
			(unlocked yes)
			(layer "F.SilkS")
			(effects
				(font
					(size 0.7874 0.5842)
					(thickness 0.1524)
				)
				(justify left)
			)
		)
		(property "Value" ""
			(at 0 0 270)
			(layer "F.Fab")
			(effects
				(font
					(size 1.27 1.27)
				)
			)
		)
		(duplicate_pad_numbers_are_jumpers no)
		(fp_line
			(start -0.7874 0.4064)
			(end -0.7874 -0.4064)
			(stroke
				(width 0.1524)
				(type default)
			)
			(layer "F.SilkS")
		)
		(fp_line
			(start 0.7874 0.4064)
			(end -0.7874 0.4064)
			(stroke
				(width 0.1524)
				(type default)
			)
			(layer "F.SilkS")
		)
		(fp_line
			(start 0 0.381)
			(end 0 -0.381)
			(stroke
				(width 0.1524)
				(type default)
			)
			(layer "F.SilkS")
		)
		(fp_line
			(start -0.7874 -0.4064)
			(end 0.7874 -0.4064)
			(stroke
				(width 0.1524)
				(type default)
			)
			(layer "F.SilkS")
		)
		(fp_line
			(start 0.7874 -0.4064)
			(end 0.7874 0.4064)
			(stroke
				(width 0.1524)
				(type default)
			)
			(layer "F.SilkS")
		)
		(fp_poly
			(pts
				(xy -0.5334 0.254) (xy -0.635 0.254) (xy -0.635 0.2286) (xy -0.635 -0.254) (xy -0.5334 -0.254) (xy -0.5334 -0.2794)
				(xy 0.5334 -0.2794) (xy 0.5334 -0.254) (xy 0.635 -0.254) (xy 0.635 0.254) (xy 0.5334 0.254) (xy 0.5334 0.2794)
				(xy -0.508 0.2794) (xy -0.5334 0.2794)
			)
			(stroke
				(width 0)
				(type default)
			)
			(fill no)
			(layer "F.CrtYd")
		)
		(pad "1" smd rect
			(at 0.40005 0 270)
			(size 0.4572 0.508)
			(layers "F.Cu" "F.Mask" "F.Paste")
			(net "P12V")
		)
		(pad "2" smd rect
			(at -0.40005 0 270)
			(size 0.4572 0.508)
			(layers "F.Cu" "F.Mask" "F.Paste")
			(net "GND")
		)
	)
	(footprint ""
		(layer "F.Cu")
		(at 72.635364 -242.026694 -90)
		(property "Reference" "C36"
			(at 0.16256 -3.77825 90)
			(unlocked yes)
			(layer "F.SilkS")
			(effects
				(font
					(size 0.7874 0.5842)
					(thickness 0.1524)
				)
			)
		)
		(property "Value" ""
			(at 0 0 270)
			(layer "F.Fab")
			(effects
				(font
					(size 1.27 1.27)
				)
			)
		)
		(duplicate_pad_numbers_are_jumpers no)
		(fp_line
			(start -1.2954 0.5842)
			(end -1.2954 -0.5842)
			(stroke
				(width 0.1524)
				(type default)
			)
			(layer "F.SilkS")
		)
		(fp_line
			(start 1.2954 0.5842)
			(end -1.2954 0.5842)
			(stroke
				(width 0.1524)
				(type default)
			)
			(layer "F.SilkS")
		)
		(fp_line
			(start -1.2954 -0.5842)
			(end 1.2954 -0.5842)
			(stroke
				(width 0.1524)
				(type default)
			)
			(layer "F.SilkS")
		)
		(fp_line
			(start 0 -0.5842)
			(end 0 0.5842)
			(stroke
				(width 0.1524)
				(type default)
			)
			(layer "F.SilkS")
		)
		(fp_line
			(start 1.2954 -0.5842)
			(end 1.2954 0.5842)
			(stroke
				(width 0.1524)
				(type default)
			)
			(layer "F.SilkS")
		)
		(fp_poly
			(pts
				(xy 0.8636 -0.4572) (xy 0.8636 -0.3556) (xy 1.143 -0.3556) (xy 1.143 0.3556) (xy 0.8636 0.3556)
				(xy 0.8636 0.4572) (xy -0.8636 0.4572) (xy -0.8636 0.3556) (xy -1.143 0.3556) (xy -1.143 -0.3556)
				(xy -0.8636 -0.3556) (xy -0.8636 -0.4572)
			)
			(stroke
				(width 0)
				(type default)
			)
			(fill no)
			(layer "F.CrtYd")
		)
		(fp_line
			(start -0.884936 0.504952)
			(end -0.884936 -0.504952)
			(stroke
				(width 0.1)
				(type default)
			)
			(layer "F.Fab")
		)
		(fp_line
			(start 0.884936 0.504952)
			(end -0.884936 0.504952)
			(stroke
				(width 0.1)
				(type default)
			)
			(layer "F.Fab")
		)
		(fp_line
			(start -0.884936 -0.504952)
			(end 0.884936 -0.504952)
			(stroke
				(width 0.1)
				(type default)
			)
			(layer "F.Fab")
		)
		(fp_line
			(start 0.884936 -0.504952)
			(end 0.884936 0.504952)
			(stroke
				(width 0.1)
				(type default)
			)
			(layer "F.Fab")
		)
		(pad "1" smd rect
			(at 0.7366 0)
			(size 0.7112 0.8128)
			(layers "F.Cu" "F.Mask" "F.Paste")
			(net "P12V")
		)
		(pad "2" smd rect
			(at -0.7366 0)
			(size 0.7112 0.8128)
			(layers "F.Cu" "F.Mask" "F.Paste")
			(net "GND")
		)
	)
	(footprint ""
		(layer "F.Cu")
		(at 69.073522 -38.821106 90)
		(property "Reference" "C12"
			(at 1.173988 -0.101854 90)
			(unlocked yes)
			(layer "F.SilkS")
			(effects
				(font
					(size 0.7874 0.5842)
					(thickness 0.1524)
				)
				(justify left)
			)
		)
		(property "Value" ""
			(at 0 0 90)
			(layer "F.Fab")
			(effects
				(font
					(size 1.27 1.27)
				)
			)
		)
		(duplicate_pad_numbers_are_jumpers no)
		(fp_line
			(start 0.7874 -0.4064)
			(end 0.7874 0.4064)
			(stroke
				(width 0.1524)
				(type default)
			)
			(layer "F.SilkS")
		)
		(fp_line
			(start -0.7874 -0.4064)
			(end 0.7874 -0.4064)
			(stroke
				(width 0.1524)
				(type default)
			)
			(layer "F.SilkS")
		)
		(fp_line
			(start 0 0.381)
			(end 0 -0.381)
			(stroke
				(width 0.1524)
				(type default)
			)
			(layer "F.SilkS")
		)
		(fp_line
			(start 0.7874 0.4064)
			(end -0.7874 0.4064)
			(stroke
				(width 0.1524)
				(type default)
			)
			(layer "F.SilkS")
		)
		(fp_line
			(start -0.7874 0.4064)
			(end -0.7874 -0.4064)
			(stroke
				(width 0.1524)
				(type default)
			)
			(layer "F.SilkS")
		)
		(fp_poly
			(pts
				(xy -0.5334 0.254) (xy -0.635 0.254) (xy -0.635 0.2286) (xy -0.635 -0.254) (xy -0.5334 -0.254) (xy -0.5334 -0.2794)
				(xy 0.5334 -0.2794) (xy 0.5334 -0.254) (xy 0.635 -0.254) (xy 0.635 0.254) (xy 0.5334 0.254) (xy 0.5334 0.2794)
				(xy -0.508 0.2794) (xy -0.5334 0.2794)
			)
			(stroke
				(width 0)
				(type default)
			)
			(fill no)
			(layer "F.CrtYd")
		)
		(pad "1" smd rect
			(at 0.40005 0 90)
			(size 0.4572 0.508)
			(layers "F.Cu" "F.Mask" "F.Paste")
			(net "P12V")
		)
		(pad "2" smd rect
			(at -0.40005 0 90)
			(size 0.4572 0.508)
			(layers "F.Cu" "F.Mask" "F.Paste")
			(net "GND")
		)
	)
	(footprint ""
		(layer "F.Cu")
		(at 2.772156 -145.957544 -90)
		(property "Reference" "R148"
			(at 1.076452 1.187704 90)
			(unlocked yes)
			(layer "F.SilkS")
			(effects
				(font
					(size 0.7874 0.5842)
					(thickness 0.1524)
				)
				(justify left)
			)
		)
		(property "Value" ""
			(at 0 0 270)
			(layer "F.Fab")
			(effects
				(font
					(size 1.27 1.27)
				)
			)
		)
		(duplicate_pad_numbers_are_jumpers no)
		(fp_line
			(start -0.7874 0.4064)
			(end -0.7874 -0.4064)
			(stroke
				(width 0.1524)
				(type default)
			)
			(layer "F.SilkS")
		)
		(fp_line
			(start 0.7874 0.4064)
			(end -0.7874 0.4064)
			(stroke
				(width 0.1524)
				(type default)
			)
			(layer "F.SilkS")
		)
		(fp_line
			(start -0.7874 -0.4064)
			(end 0.7874 -0.4064)
			(stroke
				(width 0.1524)
				(type default)
			)
			(layer "F.SilkS")
		)
		(fp_line
			(start 0.7874 -0.4064)
			(end 0.7874 0.4064)
			(stroke
				(width 0.1524)
				(type default)
			)
			(layer "F.SilkS")
		)
		(fp_poly
			(pts
				(xy -0.508 0.2794) (xy -0.508 0.2286) (xy -0.635 0.2286) (xy -0.635 -0.254) (xy -0.5334 -0.254)
				(xy -0.5334 -0.2794) (xy 0.5334 -0.2794) (xy 0.5334 -0.254) (xy 0.635 -0.254) (xy 0.635 0.254) (xy 0.5334 0.254)
				(xy 0.5334 0.2794)
			)
			(stroke
				(width 0)
				(type default)
			)
			(fill no)
			(layer "F.CrtYd")
		)
		(pad "1" smd rect
			(at 0.40005 0 270)
			(size 0.4572 0.508)
			(layers "F.Cu" "F.Mask" "F.Paste")
			(net "N42126673")
		)
		(pad "2" smd rect
			(at -0.40005 0 270)
			(size 0.4572 0.508)
			(layers "F.Cu" "F.Mask" "F.Paste")
			(net "GND")
		)
	)
	(footprint ""
		(layer "F.Cu")
		(at 49.949608 -18.56867 180)
		(property "Reference" "CE1"
			(at -4.548124 -1.308608 0)
			(unlocked yes)
			(layer "F.SilkS")
			(effects
				(font
					(size 0.7874 0.5842)
					(thickness 0.1524)
				)
				(justify left)
			)
		)
		(property "Value" ""
			(at 0 0 180)
			(layer "F.Fab")
			(effects
				(font
					(size 1.27 1.27)
				)
			)
		)
		(duplicate_pad_numbers_are_jumpers no)
		(fp_line
			(start 0 -4.2672)
			(end 0 4.2672)
			(stroke
				(width 0.1524)
				(type default)
			)
			(layer "F.SilkS")
		)
		(fp_circle
			(center 0 0)
			(end -4.2672 0)
			(stroke
				(width 0.1524)
				(type default)
			)
			(fill no)
			(layer "F.SilkS")
		)
		(fp_poly
			(pts
				(arc
					(start 0 -4.2672)
					(mid 4.2672 0)
					(end 0 4.2672)
				)
			)
			(stroke
				(width 0)
				(type default)
			)
			(fill yes)
			(layer "F.SilkS")
		)
		(fp_poly
			(pts
				(xy -2.5146 -0.762) (xy -0.9906 -0.762) (xy -0.9906 0.762) (xy -2.5146 0.762)
			)
			(stroke
				(width 0)
				(type default)
			)
			(fill no)
			(layer "B.CrtYd")
		)
		(fp_poly
			(pts
				(arc
					(start 1.7526 0.762)
					(mid 2.291415 -0.538815)
					(end 0.9906 0)
				)
				(arc
					(start 0.9906 0.0254)
					(mid 1.206345 0.546255)
					(end 1.7272 0.762)
				)
			)
			(stroke
				(width 0)
				(type default)
			)
			(fill no)
			(layer "B.CrtYd")
		)
		(fp_poly
			(pts
				(arc
					(start -4.2672 0)
					(mid 4.2672 0)
					(end -4.2672 0)
				)
			)
			(stroke
				(width 0)
				(type default)
			)
			(fill no)
			(layer "F.CrtYd")
		)
		(fp_circle
			(center 0 0)
			(end -4.2672 0)
			(stroke
				(width 0.1)
				(type default)
			)
			(fill no)
			(layer "F.Fab")
		)
		(fp_text user "+"
			(at -5.15239 -2.911348 180)
			(unlocked yes)
			(layer "F.SilkS")
			(effects
				(font
					(size 1.905 1.4224)
					(thickness 0.1524)
				)
				(justify left)
			)
		)
		(fp_text user "+"
			(at -5.6642 -0.34925 180)
			(unlocked yes)
			(layer "F.Fab")
			(effects
				(font
					(size 1.905 1.4224)
					(thickness 0.000001)
				)
				(justify left)
			)
		)
		(pad "1" thru_hole rect
			(at -1.75006 0 180)
			(size 1.397 1.397)
			(drill 0.9144)
			(layers "*.Cu" "*.Mask")
			(remove_unused_layers no)
			(net "P12V")
			(clearance 0.0127)
			(thermal_gap 0.0127)
			(padstack
				(mode front_inner_back)
				(layer "Inner"
					(shape circle)
					(size 1.397 1.397)
					(clearance 0.0127)
				)
				(layer "B.Cu"
					(shape rect)
					(size 1.397 1.397)
					(clearance 0.0127)
				)
			)
		)
		(pad "2" thru_hole circle
			(at 1.75006 0 180)
			(size 1.397 1.397)
			(drill 0.9144)
			(layers "*.Cu" "*.Mask")
			(remove_unused_layers no)
			(net "GND")
			(clearance 0.0127)
			(thermal_gap 0.0127)
		)
	)
	(footprint ""
		(layer "F.Cu")
		(at 27.244802 -19.46402 90)
		(property "Reference" "R113"
			(at -3.094482 -0.932688 90)
			(unlocked yes)
			(layer "F.SilkS")
			(effects
				(font
					(size 0.7874 0.5842)
					(thickness 0.1524)
				)
				(justify left)
			)
		)
		(property "Value" ""
			(at 0 0 90)
			(layer "F.Fab")
			(effects
				(font
					(size 1.27 1.27)
				)
			)
		)
		(duplicate_pad_numbers_are_jumpers no)
		(fp_line
			(start 0.7874 -0.4064)
			(end 0.7874 0.4064)
			(stroke
				(width 0.1524)
				(type default)
			)
			(layer "F.SilkS")
		)
		(fp_line
			(start -0.7874 -0.4064)
			(end 0.7874 -0.4064)
			(stroke
				(width 0.1524)
				(type default)
			)
			(layer "F.SilkS")
		)
		(fp_line
			(start 0.7874 0.4064)
			(end -0.7874 0.4064)
			(stroke
				(width 0.1524)
				(type default)
			)
			(layer "F.SilkS")
		)
		(fp_line
			(start -0.7874 0.4064)
			(end -0.7874 -0.4064)
			(stroke
				(width 0.1524)
				(type default)
			)
			(layer "F.SilkS")
		)
		(fp_poly
			(pts
				(xy -0.508 0.2794) (xy -0.508 0.2286) (xy -0.635 0.2286) (xy -0.635 -0.254) (xy -0.5334 -0.254)
				(xy -0.5334 -0.2794) (xy 0.5334 -0.2794) (xy 0.5334 -0.254) (xy 0.635 -0.254) (xy 0.635 0.254) (xy 0.5334 0.254)
				(xy 0.5334 0.2794)
			)
			(stroke
				(width 0)
				(type default)
			)
			(fill no)
			(layer "F.CrtYd")
		)
		(pad "1" smd rect
			(at 0.40005 0 90)
			(size 0.4572 0.508)
			(layers "F.Cu" "F.Mask" "F.Paste")
			(net "PSU1_REMOTE_N")
		)
		(pad "2" smd rect
			(at -0.40005 0 90)
			(size 0.4572 0.508)
			(layers "F.Cu" "F.Mask" "F.Paste")
			(net "PSU1_REMOTE_R2_N")
		)
	)
	(footprint ""
		(layer "F.Cu")
		(at 81.78927 -18.749772 -90)
		(property "Reference" "C7"
			(at -1.75133 -0.093726 90)
			(unlocked yes)
			(layer "F.SilkS")
			(effects
				(font
					(size 0.7874 0.5842)
					(thickness 0.1524)
				)
				(justify left)
			)
		)
		(property "Value" ""
			(at 0 0 270)
			(layer "F.Fab")
			(effects
				(font
					(size 1.27 1.27)
				)
			)
		)
		(duplicate_pad_numbers_are_jumpers no)
		(fp_line
			(start -0.7874 0.4064)
			(end -0.7874 -0.4064)
			(stroke
				(width 0.1524)
				(type default)
			)
			(layer "F.SilkS")
		)
		(fp_line
			(start 0.7874 0.4064)
			(end -0.7874 0.4064)
			(stroke
				(width 0.1524)
				(type default)
			)
			(layer "F.SilkS")
		)
		(fp_line
			(start 0 0.381)
			(end 0 -0.381)
			(stroke
				(width 0.1524)
				(type default)
			)
			(layer "F.SilkS")
		)
		(fp_line
			(start -0.7874 -0.4064)
			(end 0.7874 -0.4064)
			(stroke
				(width 0.1524)
				(type default)
			)
			(layer "F.SilkS")
		)
		(fp_line
			(start 0.7874 -0.4064)
			(end 0.7874 0.4064)
			(stroke
				(width 0.1524)
				(type default)
			)
			(layer "F.SilkS")
		)
		(fp_poly
			(pts
				(xy -0.5334 0.254) (xy -0.635 0.254) (xy -0.635 0.2286) (xy -0.635 -0.254) (xy -0.5334 -0.254) (xy -0.5334 -0.2794)
				(xy 0.5334 -0.2794) (xy 0.5334 -0.254) (xy 0.635 -0.254) (xy 0.635 0.254) (xy 0.5334 0.254) (xy 0.5334 0.2794)
				(xy -0.508 0.2794) (xy -0.5334 0.2794)
			)
			(stroke
				(width 0)
				(type default)
			)
			(fill no)
			(layer "F.CrtYd")
		)
		(pad "1" smd rect
			(at 0.40005 0 270)
			(size 0.4572 0.508)
			(layers "F.Cu" "F.Mask" "F.Paste")
			(net "P12V")
		)
		(pad "2" smd rect
			(at -0.40005 0 270)
			(size 0.4572 0.508)
			(layers "F.Cu" "F.Mask" "F.Paste")
			(net "GND")
		)
	)
	(footprint ""
		(layer "F.Cu")
		(at 74.804524 -83.335368 90)
		(property "Reference" "C18"
			(at 1.011428 0.19177 90)
			(unlocked yes)
			(layer "F.SilkS")
			(effects
				(font
					(size 0.7874 0.5842)
					(thickness 0.1524)
				)
				(justify left)
			)
		)
		(property "Value" ""
			(at 0 0 90)
			(layer "F.Fab")
			(effects
				(font
					(size 1.27 1.27)
				)
			)
		)
		(duplicate_pad_numbers_are_jumpers no)
		(fp_line
			(start 0.7874 -0.4064)
			(end 0.7874 0.4064)
			(stroke
				(width 0.1524)
				(type default)
			)
			(layer "F.SilkS")
		)
		(fp_line
			(start -0.7874 -0.4064)
			(end 0.7874 -0.4064)
			(stroke
				(width 0.1524)
				(type default)
			)
			(layer "F.SilkS")
		)
		(fp_line
			(start 0 0.381)
			(end 0 -0.381)
			(stroke
				(width 0.1524)
				(type default)
			)
			(layer "F.SilkS")
		)
		(fp_line
			(start 0.7874 0.4064)
			(end -0.7874 0.4064)
			(stroke
				(width 0.1524)
				(type default)
			)
			(layer "F.SilkS")
		)
		(fp_line
			(start -0.7874 0.4064)
			(end -0.7874 -0.4064)
			(stroke
				(width 0.1524)
				(type default)
			)
			(layer "F.SilkS")
		)
		(fp_poly
			(pts
				(xy -0.5334 0.254) (xy -0.635 0.254) (xy -0.635 0.2286) (xy -0.635 -0.254) (xy -0.5334 -0.254) (xy -0.5334 -0.2794)
				(xy 0.5334 -0.2794) (xy 0.5334 -0.254) (xy 0.635 -0.254) (xy 0.635 0.254) (xy 0.5334 0.254) (xy 0.5334 0.2794)
				(xy -0.508 0.2794) (xy -0.5334 0.2794)
			)
			(stroke
				(width 0)
				(type default)
			)
			(fill no)
			(layer "F.CrtYd")
		)
		(pad "1" smd rect
			(at 0.40005 0 90)
			(size 0.4572 0.508)
			(layers "F.Cu" "F.Mask" "F.Paste")
			(net "P12V")
		)
		(pad "2" smd rect
			(at -0.40005 0 90)
			(size 0.4572 0.508)
			(layers "F.Cu" "F.Mask" "F.Paste")
			(net "GND")
		)
	)
)
